(kicad_pcb
	(version 20260206)
	(generator "pcbnew")
	(generator_version "10.0")
	(general
		(thickness 1.6)
		(legacy_teardrops no)
	)
	(paper "A4")
	(title_block
		(title "Bryce Canyon_R.DPB_16317-1_OCP.brd")
		(comment 1 "Bryce Canyon / footprints 1159-1161 of 2099")
	)
	(layers
		(0 "F.Cu" signal "TOP")
		(4 "In1.Cu" signal "L2GND")
		(6 "In2.Cu" signal "L3")
		(8 "In3.Cu" signal "L4VCC")
		(10 "In4.Cu" signal "L5VCC")
		(12 "In5.Cu" signal "L6")
		(14 "In6.Cu" signal "L7GND")
		(2 "B.Cu" signal "BOTTOM")
		(9 "F.Adhes" user "F.Adhesive")
		(11 "B.Adhes" user "B.Adhesive")
		(13 "F.Paste" user "Package Geometry/Pastemask Top")
		(15 "B.Paste" user "Package Geometry/Pastemask Bottom")
		(5 "F.SilkS" user "Ref Des/Silkscreen Top")
		(7 "B.SilkS" user "Ref Des/Silkscreen Bottom")
		(1 "F.Mask" user "Board Geometry/Soldermask Top")
		(3 "B.Mask" user "Board Geometry/Soldermask Bottom")
		(17 "Dwgs.User" user "User.Drawings")
		(19 "Cmts.User" user "User.Comments")
		(21 "Eco1.User" user "User.Eco1")
		(23 "Eco2.User" user "User.Eco2")
		(25 "Edge.Cuts" user "Board Geometry/Outline")
		(27 "Margin" user)
		(31 "F.CrtYd" user "Package Geometry/Place Bound Top")
		(29 "B.CrtYd" user "Package Geometry/Place Bound Bottom")
		(35 "F.Fab" user "Ref Des/Assembly Top")
		(33 "B.Fab" user "Ref Des/Assembly Bottom")
	)
	(footprint ""
		(layer "F.Cu")
		(at 220.6752 -192.151 -90)
		(property "Reference" "R26"
			(at 0 0 270)
			(layer "F.SilkS")
			(hide yes)
			(effects
				(font
					(size 1.27 1.27)
				)
			)
		)
		(property "Value" "4K7R2F-GP"
			(at 0.064008 -3.993896 270)
			(unlocked yes)
			(layer "F.Fab")
			(hide yes)
			(effects
				(font
					(size 1.016 1.016)
					(thickness 0.1524)
				)
			)
		)
		(property "Device Type" "R402H16"
			(at 0.064008 -5.517896 270)
			(unlocked yes)
			(layer "F.Fab")
			(hide yes)
			(effects
				(font
					(size 1.016 1.016)
					(thickness 0.1524)
				)
			)
		)
		(duplicate_pad_numbers_are_jumpers no)
		(fp_line
			(start -0.508 -0.9398)
			(end -0.508 0.9398)
			(stroke
				(width 0.1524)
				(type default)
			)
			(layer "F.SilkS")
		)
		(fp_line
			(start 0.508 -0.9398)
			(end -0.508 -0.9398)
			(stroke
				(width 0.1524)
				(type default)
			)
			(layer "F.SilkS")
		)
		(fp_rect
			(start -0.508 0.9398)
			(end 0.508 -0.9398)
			(stroke
				(width 0)
				(type default)
			)
			(fill no)
			(layer "F.CrtYd")
		)
		(fp_rect
			(start -0.508 0.9398)
			(end 0.508 -0.9398)
			(stroke
				(width 0)
				(type default)
			)
			(fill no)
			(layer "F.Fab")
		)
		(pad "1" smd custom
			(at 0 -0.4445 270)
			(size 0.1397 0.1397)
			(layers "F.Cu" "F.Mask" "F.Paste")
			(net "P3V3_STBY_B")
			(options
				(clearance outline)
				(anchor circle)
			)
			(primitives
				(gr_poly
					(pts
						(arc
							(start -0.1778 -0.2794)
							(mid -0.249642 -0.249642)
							(end -0.2794 -0.1778)
						)
						(arc
							(start -0.2794 0.1778)
							(mid -0.249642 0.249642)
							(end -0.1778 0.2794)
						)
						(arc
							(start 0.1778 0.2794)
							(mid 0.249642 0.249642)
							(end 0.2794 0.1778)
						)
						(arc
							(start 0.2794 -0.1778)
							(mid 0.249642 -0.249642)
							(end 0.1778 -0.2794)
						)
					)
					(width 0)
					(fill yes)
				)
			)
		)
		(pad "2" smd custom
			(at 0 0.4445 270)
			(size 0.1397 0.1397)
			(layers "F.Cu" "F.Mask" "F.Paste")
			(net "IO_EXP2_HDD_FAULT_A0")
			(options
				(clearance outline)
				(anchor circle)
			)
			(primitives
				(gr_poly
					(pts
						(arc
							(start -0.1778 -0.2794)
							(mid -0.249642 -0.249642)
							(end -0.2794 -0.1778)
						)
						(arc
							(start -0.2794 0.1778)
							(mid -0.249642 0.249642)
							(end -0.1778 0.2794)
						)
						(arc
							(start 0.1778 0.2794)
							(mid 0.249642 0.249642)
							(end 0.2794 0.1778)
						)
						(arc
							(start 0.2794 -0.1778)
							(mid 0.249642 -0.249642)
							(end 0.1778 -0.2794)
						)
					)
					(width 0)
					(fill yes)
				)
			)
		)
	)
	(footprint ""
		(layer "F.Cu")
		(at 335.788 -243.586 180)
		(property "Reference" "R262"
			(at 0 0 180)
			(layer "F.SilkS")
			(hide yes)
			(effects
				(font
					(size 1.27 1.27)
				)
			)
		)
		(property "Value" "0R2J-2-GP"
			(at 0.064008 -3.993896 180)
			(unlocked yes)
			(layer "F.Fab")
			(hide yes)
			(effects
				(font
					(size 1.016 1.016)
					(thickness 0.1524)
				)
			)
		)
		(property "Device Type" "R402H16"
			(at 0.064008 -5.517896 180)
			(unlocked yes)
			(layer "F.Fab")
			(hide yes)
			(effects
				(font
					(size 1.016 1.016)
					(thickness 0.1524)
				)
			)
		)
		(duplicate_pad_numbers_are_jumpers no)
		(fp_line
			(start 0.508 -0.9398)
			(end -0.508 -0.9398)
			(stroke
				(width 0.1524)
				(type default)
			)
			(layer "F.SilkS")
		)
		(fp_line
			(start -0.508 -0.9398)
			(end -0.508 0.9398)
			(stroke
				(width 0.1524)
				(type default)
			)
			(layer "F.SilkS")
		)
		(fp_rect
			(start -0.508 0.9398)
			(end 0.508 -0.9398)
			(stroke
				(width 0)
				(type default)
			)
			(fill no)
			(layer "F.CrtYd")
		)
		(fp_rect
			(start -0.508 0.9398)
			(end 0.508 -0.9398)
			(stroke
				(width 0)
				(type default)
			)
			(fill no)
			(layer "F.Fab")
		)
		(pad "1" smd custom
			(at 0 -0.4445 180)
			(size 0.1397 0.1397)
			(layers "F.Cu" "F.Mask" "F.Paste")
			(net "DRIVE_B_6_PWR")
			(options
				(clearance outline)
				(anchor circle)
			)
			(primitives
				(gr_poly
					(pts
						(arc
							(start -0.1778 -0.2794)
							(mid -0.249642 -0.249642)
							(end -0.2794 -0.1778)
						)
						(arc
							(start -0.2794 0.1778)
							(mid -0.249642 0.249642)
							(end -0.1778 0.2794)
						)
						(arc
							(start 0.1778 0.2794)
							(mid 0.249642 0.249642)
							(end 0.2794 0.1778)
						)
						(arc
							(start 0.2794 -0.1778)
							(mid 0.249642 -0.249642)
							(end 0.1778 -0.2794)
						)
					)
					(width 0)
					(fill yes)
				)
			)
		)
		(pad "2" smd custom
			(at 0 0.4445 180)
			(size 0.1397 0.1397)
			(layers "F.Cu" "F.Mask" "F.Paste")
			(net "SW_PWR_R_HDD6")
			(options
				(clearance outline)
				(anchor circle)
			)
			(primitives
				(gr_poly
					(pts
						(arc
							(start -0.1778 -0.2794)
							(mid -0.249642 -0.249642)
							(end -0.2794 -0.1778)
						)
						(arc
							(start -0.2794 0.1778)
							(mid -0.249642 0.249642)
							(end -0.1778 0.2794)
						)
						(arc
							(start 0.1778 0.2794)
							(mid 0.249642 0.249642)
							(end 0.2794 0.1778)
						)
						(arc
							(start 0.2794 -0.1778)
							(mid 0.249642 -0.249642)
							(end 0.1778 -0.2794)
						)
					)
					(width 0)
					(fill yes)
				)
			)
		)
	)
	(footprint ""
		(layer "F.Cu")
		(at 127.113284 -130.21945 90)
		(property "Reference" "C223"
			(at 0 0 90)
			(layer "F.SilkS")
			(hide yes)
			(effects
				(font
					(size 1.27 1.27)
				)
			)
		)
		(property "Value" "SCD01U16V1KX-GP"
			(at -2.8321 -1.7399 90)
			(unlocked yes)
			(layer "F.Fab")
			(hide yes)
			(effects
				(font
					(size 1.016 1.016)
					(thickness 0.1524)
				)
			)
		)
		(property "Device Type" "C0201H13"
			(at -2.8321 -3.2639 90)
			(unlocked yes)
			(layer "F.Fab")
			(hide yes)
			(effects
				(font
					(size 1.016 1.016)
					(thickness 0.1524)
				)
			)
		)
		(duplicate_pad_numbers_are_jumpers no)
		(fp_rect
			(start -0.2794 0.6477)
			(end 0.2794 -0.6477)
			(stroke
				(width 0)
				(type default)
			)
			(fill no)
			(layer "F.CrtYd")
		)
		(fp_rect
			(start -0.2794 0.6477)
			(end 0.2794 -0.6477)
			(stroke
				(width 0)
				(type default)
			)
			(fill no)
			(layer "F.Fab")
		)
		(pad "1" smd custom
			(at 0 -0.2794 90)
			(size 0.0762 0.0762)
			(layers "F.Cu" "F.Mask" "F.Paste")
			(net "SAS_HDD_RX_N15")
			(options
				(clearance outline)
				(anchor circle)
			)
			(primitives
				(gr_poly
					(pts
						(arc
							(start 0.1524 -0.127)
							(mid 0.137521 -0.162921)
							(end 0.1016 -0.1778)
						)
						(arc
							(start -0.1016 -0.1778)
							(mid -0.137521 -0.162921)
							(end -0.1524 -0.127)
						)
						(arc
							(start -0.1524 0.127)
							(mid -0.137521 0.162921)
							(end -0.1016 0.1778)
						)
						(arc
							(start 0.1016 0.1778)
							(mid 0.137521 0.162921)
							(end 0.1524 0.127)
						)
					)
					(width 0)
					(fill yes)
				)
			)
		)
		(pad "2" smd custom
			(at 0 0.2794 90)
			(size 0.0762 0.0762)
			(layers "F.Cu" "F.Mask" "F.Paste")
			(net "PHY_SCC_B_TO_DRV_B_15_DN")
			(options
				(clearance outline)
				(anchor circle)
			)
			(primitives
				(gr_poly
					(pts
						(arc
							(start 0.1524 -0.127)
							(mid 0.137521 -0.162921)
							(end 0.1016 -0.1778)
						)
						(arc
							(start -0.1016 -0.1778)
							(mid -0.137521 -0.162921)
							(end -0.1524 -0.127)
						)
						(arc
							(start -0.1524 0.127)
							(mid -0.137521 0.162921)
							(end -0.1016 0.1778)
						)
						(arc
							(start 0.1016 0.1778)
							(mid 0.137521 0.162921)
							(end 0.1524 0.127)
						)
					)
					(width 0)
					(fill yes)
				)
			)
		)
	)
)
